(kicad_pcb
	(version 20260206)
	(generator "pcbnew")
	(generator_version "10.0")
	(general
		(thickness 1.6)
		(legacy_teardrops no)
	)
	(paper "A4")
	(title_block
		(title "01162023_DA0F0TEBIF0_F0T_Expander_BD_F_brd_V02_OCP.brd")
		(comment 1 "Grand Teton / footprints 38-40 of 9728")
	)
	(layers
		(0 "F.Cu" signal "TOP")
		(4 "In1.Cu" signal "GND")
		(6 "In2.Cu" signal "VCC")
		(8 "In3.Cu" signal "VCC1")
		(10 "In4.Cu" signal "GND1")
		(12 "In5.Cu" signal "IN1")
		(14 "In6.Cu" signal "GND2")
		(16 "In7.Cu" signal "IN2")
		(18 "In8.Cu" signal "GND3")
		(20 "In9.Cu" signal "IN3")
		(22 "In10.Cu" signal "GND4")
		(24 "In11.Cu" signal "IN4")
		(26 "In12.Cu" signal "GND5")
		(28 "In13.Cu" signal "IN5")
		(30 "In14.Cu" signal "GND6")
		(32 "In15.Cu" signal "IN6")
		(34 "In16.Cu" signal "GND7")
		(2 "B.Cu" signal "BOTTOM")
		(9 "F.Adhes" user "F.Adhesive")
		(11 "B.Adhes" user "B.Adhesive")
		(13 "F.Paste" user "Package Geometry/Pastemask Top")
		(15 "B.Paste" user "Package Geometry/Pastemask Bottom")
		(5 "F.SilkS" user "Ref Des/Silkscreen Top")
		(7 "B.SilkS" user "Ref Des/Silkscreen Bottom")
		(1 "F.Mask" user "Board Geometry/Soldermask Top")
		(3 "B.Mask" user "Board Geometry/Soldermask Bottom")
		(17 "Dwgs.User" user "User.Drawings")
		(19 "Cmts.User" user "User.Comments")
		(21 "Eco1.User" user "User.Eco1")
		(23 "Eco2.User" user "User.Eco2")
		(25 "Edge.Cuts" user "Board Geometry/Outline")
		(27 "Margin" user)
		(31 "F.CrtYd" user "Package Geometry/Place Bound Top")
		(29 "B.CrtYd" user "Package Geometry/Place Bound Bottom")
		(35 "F.Fab" user "Ref Des/Assembly Top")
		(33 "B.Fab" user "Ref Des/Assembly Bottom")
	)
	(footprint ""
		(layer "F.Cu")
		(at 234.021122 -92.266516 90)
		(property "Reference" "U112"
			(at 0 0 90)
			(layer "F.SilkS")
			(hide yes)
			(effects
				(font
					(size 1.27 1.27)
				)
			)
		)
		(property "Value" ""
			(at 0 0 90)
			(layer "F.Fab")
			(effects
				(font
					(size 1.27 1.27)
				)
			)
		)
		(duplicate_pad_numbers_are_jumpers no)
		(fp_line
			(start 0 -2.921)
			(end 0 -3.302)
			(stroke
				(width 0.1524)
				(type default)
			)
			(layer "F.SilkS")
		)
		(fp_line
			(start 2.500122 -2.500122)
			(end 2.500122 -1.778)
			(stroke
				(width 0.1524)
				(type default)
			)
			(layer "F.SilkS")
		)
		(fp_line
			(start 1.778 -2.500122)
			(end 2.500122 -2.500122)
			(stroke
				(width 0.1524)
				(type default)
			)
			(layer "F.SilkS")
		)
		(fp_line
			(start -2.500122 -2.500122)
			(end -1.778 -2.500122)
			(stroke
				(width 0.1524)
				(type default)
			)
			(layer "F.SilkS")
		)
		(fp_line
			(start -2.500122 -1.778)
			(end -2.500122 -2.500122)
			(stroke
				(width 0.1524)
				(type default)
			)
			(layer "F.SilkS")
		)
		(fp_line
			(start 2.921 -1.016)
			(end 3.683 -1.016)
			(stroke
				(width 0.1524)
				(type default)
			)
			(layer "F.SilkS")
		)
		(fp_line
			(start -2.921 0.508)
			(end -3.302 0.508)
			(stroke
				(width 0.1524)
				(type default)
			)
			(layer "F.SilkS")
		)
		(fp_line
			(start 2.921 1.524)
			(end 3.302 1.524)
			(stroke
				(width 0.1524)
				(type default)
			)
			(layer "F.SilkS")
		)
		(fp_line
			(start 2.500122 1.778)
			(end 2.500122 2.500122)
			(stroke
				(width 0.1524)
				(type default)
			)
			(layer "F.SilkS")
		)
		(fp_line
			(start 2.500122 2.500122)
			(end 1.778 2.500122)
			(stroke
				(width 0.1524)
				(type default)
			)
			(layer "F.SilkS")
		)
		(fp_line
			(start -1.778 2.500122)
			(end -2.500122 2.500122)
			(stroke
				(width 0.1524)
				(type default)
			)
			(layer "F.SilkS")
		)
		(fp_line
			(start -2.500122 2.500122)
			(end -2.500122 1.778)
			(stroke
				(width 0.1524)
				(type default)
			)
			(layer "F.SilkS")
		)
		(fp_line
			(start -0.508 2.921)
			(end -0.508 3.683)
			(stroke
				(width 0.1524)
				(type default)
			)
			(layer "F.SilkS")
		)
		(fp_poly
			(pts
				(xy -2.883408 -2.518918) (xy -2.632964 -1.768602) (xy -3.383534 -2.018792)
			)
			(stroke
				(width 0)
				(type default)
			)
			(fill yes)
			(layer "F.SilkS")
		)
		(fp_line
			(start 0 -2.921)
			(end 0 -3.302)
			(stroke
				(width 0.1)
				(type default)
			)
			(layer "F.Fab")
		)
		(fp_line
			(start 2.500122 -2.500122)
			(end 2.500122 2.500122)
			(stroke
				(width 0.1)
				(type default)
			)
			(layer "F.Fab")
		)
		(fp_line
			(start -2.500122 -2.500122)
			(end 2.500122 -2.500122)
			(stroke
				(width 0.1)
				(type default)
			)
			(layer "F.Fab")
		)
		(fp_line
			(start 2.921 -1.016)
			(end 3.683 -1.016)
			(stroke
				(width 0.1)
				(type default)
			)
			(layer "F.Fab")
		)
		(fp_line
			(start -2.921 0.508)
			(end -3.302 0.508)
			(stroke
				(width 0.1)
				(type default)
			)
			(layer "F.Fab")
		)
		(fp_line
			(start 2.921 1.524)
			(end 3.302 1.524)
			(stroke
				(width 0.1)
				(type default)
			)
			(layer "F.Fab")
		)
		(fp_line
			(start 2.500122 2.500122)
			(end -2.500122 2.500122)
			(stroke
				(width 0.1)
				(type default)
			)
			(layer "F.Fab")
		)
		(fp_line
			(start -2.500122 2.500122)
			(end -2.500122 -2.500122)
			(stroke
				(width 0.1)
				(type default)
			)
			(layer "F.Fab")
		)
		(fp_line
			(start -0.508 2.921)
			(end -0.508 3.683)
			(stroke
				(width 0.1)
				(type default)
			)
			(layer "F.Fab")
		)
		(fp_poly
			(pts
				(xy -3.7592 -1.933194) (xy -2.892806 -1.500124) (xy -3.7592 -1.0668)
			)
			(stroke
				(width 0)
				(type default)
			)
			(fill yes)
			(layer "F.Fab")
		)
		(fp_text user "28"
			(at -2.241804 -3.229356 90)
			(unlocked yes)
			(layer "F.SilkS")
			(effects
				(font
					(size 0.635 0.4064)
					(thickness 0.1524)
				)
			)
		)
		(fp_text user "22"
			(at 2.2352 -3.172968 90)
			(unlocked yes)
			(layer "F.SilkS")
			(effects
				(font
					(size 0.635 0.4064)
					(thickness 0.1524)
				)
			)
		)
		(fp_text user "21"
			(at 3.227832 -2.2606 180)
			(unlocked yes)
			(layer "F.SilkS")
			(effects
				(font
					(size 0.635 0.4064)
					(thickness 0.1524)
				)
			)
		)
		(fp_text user "7"
			(at -3.147568 1.8034 180)
			(unlocked yes)
			(layer "F.SilkS")
			(effects
				(font
					(size 0.635 0.4064)
					(thickness 0.1524)
				)
			)
		)
		(fp_text user "15"
			(at 3.253232 2.2352 180)
			(unlocked yes)
			(layer "F.SilkS")
			(effects
				(font
					(size 0.635 0.4064)
					(thickness 0.1524)
				)
			)
		)
		(fp_text user "14"
			(at 2.1336 3.253232 90)
			(unlocked yes)
			(layer "F.SilkS")
			(effects
				(font
					(size 0.635 0.4064)
					(thickness 0.1524)
				)
			)
		)
		(fp_text user "8"
			(at -1.8796 3.253232 90)
			(unlocked yes)
			(layer "F.SilkS")
			(effects
				(font
					(size 0.635 0.4064)
					(thickness 0.1524)
				)
			)
		)
		(fp_text user "22"
			(at 2.2352 -3.172968 90)
			(unlocked yes)
			(layer "F.Fab")
			(effects
				(font
					(size 0.635 0.4064)
					(thickness 0.1524)
				)
			)
		)
		(fp_text user "28"
			(at -2.2098 -3.172968 90)
			(unlocked yes)
			(layer "F.Fab")
			(effects
				(font
					(size 0.635 0.4064)
					(thickness 0.1524)
				)
			)
		)
		(fp_text user "21"
			(at 3.227832 -2.2606 180)
			(unlocked yes)
			(layer "F.Fab")
			(effects
				(font
					(size 0.635 0.4064)
					(thickness 0.1524)
				)
			)
		)
		(fp_text user "7"
			(at -3.147568 1.8034 180)
			(unlocked yes)
			(layer "F.Fab")
			(effects
				(font
					(size 0.635 0.4064)
					(thickness 0.1524)
				)
			)
		)
		(fp_text user "15"
			(at 3.253232 2.2352 180)
			(unlocked yes)
			(layer "F.Fab")
			(effects
				(font
					(size 0.635 0.4064)
					(thickness 0.1524)
				)
			)
		)
		(fp_text user "14"
			(at 2.1336 3.253232 90)
			(unlocked yes)
			(layer "F.Fab")
			(effects
				(font
					(size 0.635 0.4064)
					(thickness 0.1524)
				)
			)
		)
		(fp_text user "8"
			(at -1.8796 3.253232 90)
			(unlocked yes)
			(layer "F.Fab")
			(effects
				(font
					(size 0.635 0.4064)
					(thickness 0.1524)
				)
			)
		)
		(pad "1" smd rect
			(at -2.412492 -1.500124 180)
			(size 0.254 0.7366)
			(layers "F.Cu" "F.Mask" "F.Paste")
			(net "USB2_PEX_HUB_R_DN")
		)
		(pad "2" smd rect
			(at -2.412492 -0.999998 180)
			(size 0.254 0.7366)
			(layers "F.Cu" "F.Mask" "F.Paste")
			(net "USB2_PEX_HUB_R_DP")
		)
		(pad "3" smd rect
			(at -2.412492 -0.499872 180)
			(size 0.254 0.7366)
			(layers "F.Cu" "F.Mask" "F.Paste")
			(net "USB2_FT4232_SDB_R_DN")
		)
		(pad "4" smd rect
			(at -2.412492 0 180)
			(size 0.254 0.7366)
			(layers "F.Cu" "F.Mask" "F.Paste")
			(net "USB2_FT4232_SDB_R_DP")
		)
		(pad "5" smd rect
			(at -2.412492 0.499872 180)
			(size 0.254 0.7366)
			(layers "F.Cu" "F.Mask" "F.Paste")
			(net "P3V3_PEX_USB_HUB")
		)
		(pad "6" smd rect
			(at -2.412492 0.999998 180)
			(size 0.254 0.7366)
			(layers "F.Cu" "F.Mask" "F.Paste")
			(net "USB2_FT4232_CLI_R_DN")
		)
		(pad "7" smd rect
			(at -2.412492 1.500124 180)
			(size 0.254 0.7366)
			(layers "F.Cu" "F.Mask" "F.Paste")
			(net "USB2_FT4232_CLI_R_DP")
		)
		(pad "8" smd rect
			(at -1.500124 2.412492 90)
			(size 0.254 0.7366)
			(layers "F.Cu" "F.Mask" "F.Paste")
			(net "PEX_USB_HUB_RREF")
		)
		(pad "9" smd rect
			(at -0.999998 2.412492 90)
			(size 0.254 0.7366)
			(layers "F.Cu" "F.Mask" "F.Paste")
			(net "P3V3_PEX_USB_HUB")
		)
		(pad "10" smd rect
			(at -0.499872 2.412492 90)
			(size 0.254 0.7366)
			(layers "F.Cu" "F.Mask" "F.Paste")
			(net "PEX_USB_HUB_XIN")
		)
		(pad "11" smd rect
			(at 0 2.412492 90)
			(size 0.254 0.7366)
			(layers "F.Cu" "F.Mask" "F.Paste")
			(net "PEX_USB_HUB_XOUT")
		)
		(pad "12" smd rect
			(at 0.499872 2.412492 90)
			(size 0.254 0.7366)
			(layers "F.Cu" "F.Mask" "F.Paste")
			(net "Net_4251")
		)
		(pad "13" smd rect
			(at 0.999998 2.412492 90)
			(size 0.254 0.7366)
			(layers "F.Cu" "F.Mask" "F.Paste")
			(net "Net_4253")
		)
		(pad "14" smd rect
			(at 1.500124 2.412492 90)
			(size 0.254 0.7366)
			(layers "F.Cu" "F.Mask" "F.Paste")
			(net "P3V3_PEX_USB_HUB")
		)
		(pad "15" smd rect
			(at 2.412492 1.500124 180)
			(size 0.254 0.7366)
			(layers "F.Cu" "F.Mask" "F.Paste")
			(net "Net_4252")
		)
		(pad "16" smd rect
			(at 2.412492 0.999998 180)
			(size 0.254 0.7366)
			(layers "F.Cu" "F.Mask" "F.Paste")
			(net "Net_4254")
		)
		(pad "17" smd rect
			(at 2.412492 0.499872 180)
			(size 0.254 0.7366)
			(layers "F.Cu" "F.Mask" "F.Paste")
			(net "RST_PEX_USB_HUB_R_N")
		)
		(pad "18" smd rect
			(at 2.412492 0 180)
			(size 0.254 0.7366)
			(layers "F.Cu" "F.Mask" "F.Paste")
			(net "PEX_USB_HUB_TEST")
		)
		(pad "19" smd rect
			(at 2.412492 -0.499872 180)
			(size 0.254 0.7366)
			(layers "F.Cu" "F.Mask" "F.Paste")
			(net "PEX_USB_HUB_OVCUR4")
		)
		(pad "20" smd rect
			(at 2.412492 -0.999998 180)
			(size 0.254 0.7366)
			(layers "F.Cu" "F.Mask" "F.Paste")
			(net "PEX_USB_HUB_OVCUR3")
		)
		(pad "21" smd rect
			(at 2.412492 -1.500124 180)
			(size 0.254 0.7366)
			(layers "F.Cu" "F.Mask" "F.Paste")
			(net "P3V3_PEX_USB_HUB")
		)
		(pad "22" smd rect
			(at 1.500124 -2.412492 90)
			(size 0.254 0.7366)
			(layers "F.Cu" "F.Mask" "F.Paste")
			(net "PEX_USB_HUB_PSELF")
		)
		(pad "23" smd rect
			(at 0.999998 -2.412492 90)
			(size 0.254 0.7366)
			(layers "F.Cu" "F.Mask" "F.Paste")
			(net "PEX_USB_HUB_PGANG")
		)
		(pad "24" smd rect
			(at 0.499872 -2.412492 90)
			(size 0.254 0.7366)
			(layers "F.Cu" "F.Mask" "F.Paste")
			(net "PEX_USB_HUB_OVCUR2")
		)
		(pad "25" smd rect
			(at 0 -2.412492 90)
			(size 0.254 0.7366)
			(layers "F.Cu" "F.Mask" "F.Paste")
			(net "PEX_USB_HUB_OVCUR1")
		)
		(pad "26" smd rect
			(at -0.499872 -2.412492 90)
			(size 0.254 0.7366)
			(layers "F.Cu" "F.Mask" "F.Paste")
			(net "Net_4255")
		)
		(pad "27" smd rect
			(at -0.999998 -2.412492 90)
			(size 0.254 0.7366)
			(layers "F.Cu" "F.Mask" "F.Paste")
			(net "P3V3_PEX_USB_HUB")
		)
		(pad "28" smd rect
			(at -1.500124 -2.412492 90)
			(size 0.254 0.7366)
			(layers "F.Cu" "F.Mask" "F.Paste")
			(net "P3V3_PEX_USB_HUB")
		)
		(pad "TH" smd rect
			(at 0 0 90)
			(size 3.556 3.556)
			(layers "F.Cu" "F.Mask" "F.Paste")
			(net "GND")
		)
		(zone
			(layer "F.Cu")
			(hatch none 0.5)
			(connect_pads
				(clearance 0)
			)
			(min_thickness 0.25)
			(keepout
				(tracks not_allowed)
				(vias allowed)
				(pads allowed)
				(copperpour not_allowed)
				(footprints allowed)
			)
			(placement
				(enabled no)
				(sheetname "")
			)
			(fill
				(thermal_gap 0.5)
				(thermal_bridge_width 0.5)
				(island_removal_mode 0)
			)
			(polygon
				(pts
					(xy 232.039922 -93.206316) (xy 232.192322 -93.206316) (xy 232.192322 -90.437716) (xy 235.849922 -90.437716)
					(xy 235.849922 -94.095316) (xy 232.192322 -94.095316) (xy 232.192322 -93.231716) (xy 232.039922 -93.231716)
					(xy 232.039922 -94.247716) (xy 236.002322 -94.247716) (xy 236.002322 -90.285316) (xy 232.039922 -90.285316)
				)
			)
		)
	)
	(footprint ""
		(layer "F.Cu")
		(at 144.261332 -389.58901 90)
		(property "Reference" "C4106"
			(at 0 0 90)
			(layer "F.SilkS")
			(hide yes)
			(effects
				(font
					(size 1.27 1.27)
				)
			)
		)
		(property "Value" ""
			(at 0 0 90)
			(layer "F.Fab")
			(effects
				(font
					(size 1.27 1.27)
				)
			)
		)
		(duplicate_pad_numbers_are_jumpers no)
		(fp_line
			(start 0.7874 -0.4064)
			(end 0.7874 0.4064)
			(stroke
				(width 0.1524)
				(type default)
			)
			(layer "F.SilkS")
		)
		(fp_line
			(start -0.7874 -0.4064)
			(end 0.7874 -0.4064)
			(stroke
				(width 0.1524)
				(type default)
			)
			(layer "F.SilkS")
		)
		(fp_line
			(start 0.7874 0.4064)
			(end -0.7874 0.4064)
			(stroke
				(width 0.1524)
				(type default)
			)
			(layer "F.SilkS")
		)
		(fp_line
			(start -0.7874 0.4064)
			(end -0.7874 -0.4064)
			(stroke
				(width 0.1524)
				(type default)
			)
			(layer "F.SilkS")
		)
		(fp_line
			(start -0.12065 -0.305054)
			(end -0.12065 -0.2794)
			(stroke
				(width 0.1)
				(type default)
			)
			(layer "F.Fab")
		)
		(fp_line
			(start -0.67945 -0.305054)
			(end -0.12065 -0.305054)
			(stroke
				(width 0.1)
				(type default)
			)
			(layer "F.Fab")
		)
		(fp_line
			(start 0.67945 -0.3048)
			(end 0.67945 0.3048)
			(stroke
				(width 0.1)
				(type default)
			)
			(layer "F.Fab")
		)
		(fp_line
			(start 0.12065 -0.3048)
			(end 0.67945 -0.3048)
			(stroke
				(width 0.1)
				(type default)
			)
			(layer "F.Fab")
		)
		(fp_line
			(start 0.12065 -0.2794)
			(end 0.12065 -0.3048)
			(stroke
				(width 0.1)
				(type default)
			)
			(layer "F.Fab")
		)
		(fp_line
			(start -0.12065 -0.2794)
			(end 0.12065 -0.2794)
			(stroke
				(width 0.1)
				(type default)
			)
			(layer "F.Fab")
		)
		(fp_line
			(start 0.120396 0.2794)
			(end -0.12065 0.2794)
			(stroke
				(width 0.1)
				(type default)
			)
			(layer "F.Fab")
		)
		(fp_line
			(start -0.12065 0.2794)
			(end -0.12065 0.3048)
			(stroke
				(width 0.1)
				(type default)
			)
			(layer "F.Fab")
		)
		(fp_line
			(start 0.67945 0.3048)
			(end 0.120396 0.3048)
			(stroke
				(width 0.1)
				(type default)
			)
			(layer "F.Fab")
		)
		(fp_line
			(start 0.120396 0.3048)
			(end 0.120396 0.2794)
			(stroke
				(width 0.1)
				(type default)
			)
			(layer "F.Fab")
		)
		(fp_line
			(start -0.12065 0.3048)
			(end -0.67945 0.3048)
			(stroke
				(width 0.1)
				(type default)
			)
			(layer "F.Fab")
		)
		(fp_line
			(start -0.67945 0.3048)
			(end -0.67945 -0.305054)
			(stroke
				(width 0.1)
				(type default)
			)
			(layer "F.Fab")
		)
		(pad "1" smd circle
			(at -0.40005 0 90)
			(size 0 0)
			(layers "F.Cu" "F.Mask" "F.Paste")
			(net "GND")
		)
		(pad "2" smd circle
			(at 0.40005 0 90)
			(size 0 0)
			(layers "F.Cu" "F.Mask" "F.Paste")
			(net "SMB_GPU1_ALERT_N")
		)
	)
	(footprint ""
		(layer "F.Cu")
		(at 383.818384 -250.070874 -90)
		(property "Reference" "R1417"
			(at 0 0 270)
			(layer "F.SilkS")
			(hide yes)
			(effects
				(font
					(size 1.27 1.27)
				)
			)
		)
		(property "Value" ""
			(at 0 0 270)
			(layer "F.Fab")
			(effects
				(font
					(size 1.27 1.27)
				)
			)
		)
		(duplicate_pad_numbers_are_jumpers no)
		(fp_line
			(start -0.7874 0.4064)
			(end -0.7874 -0.4064)
			(stroke
				(width 0.1524)
				(type default)
			)
			(layer "F.SilkS")
		)
		(fp_line
			(start 0.7874 0.4064)
			(end -0.7874 0.4064)
			(stroke
				(width 0.1524)
				(type default)
			)
			(layer "F.SilkS")
		)
		(fp_line
			(start -0.7874 -0.4064)
			(end 0.7874 -0.4064)
			(stroke
				(width 0.1524)
				(type default)
			)
			(layer "F.SilkS")
		)
		(fp_line
			(start 0.7874 -0.4064)
			(end 0.7874 0.4064)
			(stroke
				(width 0.1524)
				(type default)
			)
			(layer "F.SilkS")
		)
		(fp_line
			(start -0.67945 0.3048)
			(end -0.67945 -0.305054)
			(stroke
				(width 0.1)
				(type default)
			)
			(layer "F.Fab")
		)
		(fp_line
			(start -0.12065 0.3048)
			(end -0.67945 0.3048)
			(stroke
				(width 0.1)
				(type default)
			)
			(layer "F.Fab")
		)
		(fp_line
			(start 0.120396 0.3048)
			(end 0.120396 0.2794)
			(stroke
				(width 0.1)
				(type default)
			)
			(layer "F.Fab")
		)
		(fp_line
			(start 0.67945 0.3048)
			(end 0.120396 0.3048)
			(stroke
				(width 0.1)
				(type default)
			)
			(layer "F.Fab")
		)
		(fp_line
			(start -0.12065 0.2794)
			(end -0.12065 0.3048)
			(stroke
				(width 0.1)
				(type default)
			)
			(layer "F.Fab")
		)
		(fp_line
			(start 0.120396 0.2794)
			(end -0.12065 0.2794)
			(stroke
				(width 0.1)
				(type default)
			)
			(layer "F.Fab")
		)
		(fp_line
			(start -0.12065 -0.2794)
			(end 0.12065 -0.2794)
			(stroke
				(width 0.1)
				(type default)
			)
			(layer "F.Fab")
		)
		(fp_line
			(start 0.12065 -0.2794)
			(end 0.12065 -0.3048)
			(stroke
				(width 0.1)
				(type default)
			)
			(layer "F.Fab")
		)
		(fp_line
			(start 0.12065 -0.3048)
			(end 0.67945 -0.3048)
			(stroke
				(width 0.1)
				(type default)
			)
			(layer "F.Fab")
		)
		(fp_line
			(start 0.67945 -0.3048)
			(end 0.67945 0.3048)
			(stroke
				(width 0.1)
				(type default)
			)
			(layer "F.Fab")
		)
		(fp_line
			(start -0.67945 -0.305054)
			(end -0.12065 -0.305054)
			(stroke
				(width 0.1)
				(type default)
			)
			(layer "F.Fab")
		)
		(fp_line
			(start -0.12065 -0.305054)
			(end -0.12065 -0.2794)
			(stroke
				(width 0.1)
				(type default)
			)
			(layer "F.Fab")
		)
		(pad "1" smd circle
			(at -0.40005 0 270)
			(size 0 0)
			(layers "F.Cu" "F.Mask" "F.Paste")
			(net "PEX3_MODE_SEL12")
		)
		(pad "2" smd circle
			(at 0.40005 0 270)
			(size 0 0)
			(layers "F.Cu" "F.Mask" "F.Paste")
			(net "P1V8_PEX")
		)
	)
)
